(kicad_pcb
	(version 20260206)
	(generator "pcbnew")
	(generator_version "10.0")
	(general
		(thickness 1.6)
		(legacy_teardrops no)
	)
	(paper "A4")
	(title_block
		(title "9054_F0T_PDB_BD_GPU_F_V04_1213_1550_OCP.brd")
		(comment 1 "Grand Teton / footprints 552-557 of 608")
	)
	(layers
		(0 "F.Cu" signal "TOP")
		(4 "In1.Cu" signal "GND")
		(6 "In2.Cu" signal "IN1")
		(8 "In3.Cu" signal "GND1")
		(10 "In4.Cu" signal "VCC")
		(12 "In5.Cu" signal "VCC1")
		(14 "In6.Cu" signal "GND2")
		(16 "In7.Cu" signal "IN2")
		(18 "In8.Cu" signal "GND3")
		(2 "B.Cu" signal "BOTTOM")
		(9 "F.Adhes" user "F.Adhesive")
		(11 "B.Adhes" user "B.Adhesive")
		(13 "F.Paste" user "Package Geometry/Pastemask Top")
		(15 "B.Paste" user "Package Geometry/Pastemask Bottom")
		(5 "F.SilkS" user "Ref Des/Silkscreen Top")
		(7 "B.SilkS" user "Ref Des/Silkscreen Bottom")
		(1 "F.Mask" user "Board Geometry/Soldermask Top")
		(3 "B.Mask" user "Board Geometry/Soldermask Bottom")
		(17 "Dwgs.User" user "User.Drawings")
		(19 "Cmts.User" user "User.Comments")
		(21 "Eco1.User" user "User.Eco1")
		(23 "Eco2.User" user "User.Eco2")
		(25 "Edge.Cuts" user "Board Geometry/Outline")
		(27 "Margin" user)
		(31 "F.CrtYd" user "Package Geometry/Place Bound Top")
		(29 "B.CrtYd" user "Package Geometry/Place Bound Bottom")
		(35 "F.Fab" user "Ref Des/Assembly Top")
		(33 "B.Fab" user "Ref Des/Assembly Bottom")
	)
	(footprint ""
		(layer "B.Cu")
		(at 287.9344 -78.486)
		(property "Reference" "U31"
			(at 3.50393 -1.905 270)
			(unlocked yes)
			(layer "B.SilkS")
			(effects
				(font
					(size 0.7874 0.5842)
					(thickness 0.1524)
				)
				(justify left mirror)
			)
		)
		(property "Value" ""
			(at 0 0 0)
			(layer "B.Fab")
			(effects
				(font
					(size 1.27 1.27)
				)
				(justify mirror)
			)
		)
		(duplicate_pad_numbers_are_jumpers no)
		(fp_line
			(start -2.249932 -1.549908)
			(end -0.737108 -1.549908)
			(stroke
				(width 0.1524)
				(type default)
			)
			(layer "B.SilkS")
		)
		(fp_line
			(start -2.249932 1.549908)
			(end -2.249932 -1.549908)
			(stroke
				(width 0.1524)
				(type default)
			)
			(layer "B.SilkS")
		)
		(fp_line
			(start -0.737108 -1.549908)
			(end 0 -0.8128)
			(stroke
				(width 0.1524)
				(type default)
			)
			(layer "B.SilkS")
		)
		(fp_line
			(start 0 -0.8128)
			(end 0.737108 -1.549908)
			(stroke
				(width 0.1524)
				(type default)
			)
			(layer "B.SilkS")
		)
		(fp_line
			(start 0.737108 -1.549908)
			(end 2.249932 -1.549908)
			(stroke
				(width 0.1524)
				(type default)
			)
			(layer "B.SilkS")
		)
		(fp_line
			(start 2.249932 -1.549908)
			(end 2.249932 1.549908)
			(stroke
				(width 0.1524)
				(type default)
			)
			(layer "B.SilkS")
		)
		(fp_line
			(start 2.249932 1.549908)
			(end -2.249932 1.549908)
			(stroke
				(width 0.1524)
				(type default)
			)
			(layer "B.SilkS")
		)
		(fp_poly
			(pts
				(xy 4.7498 -0.467106) (xy 4.7498 -1.483106) (xy 3.7338 -0.975106)
			)
			(stroke
				(width 0)
				(type default)
			)
			(fill yes)
			(layer "B.SilkS")
		)
		(fp_line
			(start -2.249932 -1.549908)
			(end 2.249932 -1.549908)
			(stroke
				(width 0.1)
				(type default)
			)
			(layer "B.Fab")
		)
		(fp_line
			(start -2.249932 1.549908)
			(end -2.249932 -1.549908)
			(stroke
				(width 0.1)
				(type default)
			)
			(layer "B.Fab")
		)
		(fp_line
			(start 2.249932 -1.549908)
			(end 2.249932 1.549908)
			(stroke
				(width 0.1)
				(type default)
			)
			(layer "B.Fab")
		)
		(fp_line
			(start 2.249932 1.549908)
			(end -2.249932 1.549908)
			(stroke
				(width 0.1)
				(type default)
			)
			(layer "B.Fab")
		)
		(fp_poly
			(pts
				(xy 4.7498 -0.467106) (xy 4.7498 -1.483106) (xy 3.7338 -0.975106)
			)
			(stroke
				(width 0)
				(type default)
			)
			(fill yes)
			(layer "B.Fab")
		)
		(pad "1" smd rect
			(at 3.052572 -0.975106 270)
			(size 0.381 1.1684)
			(layers "B.Cu" "B.Mask" "B.Paste")
			(net "P52V_HS1_CS")
		)
		(pad "2" smd rect
			(at 3.052572 -0.32512 270)
			(size 0.381 1.1684)
			(layers "B.Cu" "B.Mask" "B.Paste")
			(net "P52V_HS1_SIO")
		)
		(pad "3" smd rect
			(at 3.052572 0.32512 270)
			(size 0.381 1.1684)
			(layers "B.Cu" "B.Mask" "B.Paste")
			(net "P52V_HS1_DVCC")
		)
		(pad "4" smd rect
			(at 3.052572 0.975106 270)
			(size 0.381 1.1684)
			(layers "B.Cu" "B.Mask" "B.Paste")
			(net "GND")
		)
		(pad "5" smd rect
			(at -3.052572 0.975106 270)
			(size 0.381 1.1684)
			(layers "B.Cu" "B.Mask" "B.Paste")
			(net "P52V_HS1_SIO")
		)
		(pad "6" smd rect
			(at -3.052572 0.32512 270)
			(size 0.381 1.1684)
			(layers "B.Cu" "B.Mask" "B.Paste")
			(net "P52V_HS1_SCK")
		)
		(pad "7" smd rect
			(at -3.052572 -0.32512 270)
			(size 0.381 1.1684)
			(layers "B.Cu" "B.Mask" "B.Paste")
			(net "P52V_HS1_DVCC")
		)
		(pad "8" smd rect
			(at -3.052572 -0.975106 270)
			(size 0.381 1.1684)
			(layers "B.Cu" "B.Mask" "B.Paste")
			(net "P52V_HS1_DVCC")
		)
	)
	(footprint ""
		(layer "B.Cu")
		(at 293.2684 -76.454 -90)
		(property "Reference" "PC6"
			(at 0 0 90)
			(layer "B.SilkS")
			(hide yes)
			(effects
				(font
					(size 1.27 1.27)
				)
				(justify mirror)
			)
		)
		(property "Value" ""
			(at 0 0 90)
			(layer "B.Fab")
			(effects
				(font
					(size 1.27 1.27)
				)
				(justify mirror)
			)
		)
		(duplicate_pad_numbers_are_jumpers no)
		(fp_line
			(start -0.7874 0.4064)
			(end 0.7874 0.4064)
			(stroke
				(width 0.1524)
				(type default)
			)
			(layer "B.SilkS")
		)
		(fp_line
			(start 0.7874 0.4064)
			(end 0.7874 -0.4064)
			(stroke
				(width 0.1524)
				(type default)
			)
			(layer "B.SilkS")
		)
		(fp_line
			(start -0.7874 -0.4064)
			(end -0.7874 0.4064)
			(stroke
				(width 0.1524)
				(type default)
			)
			(layer "B.SilkS")
		)
		(fp_line
			(start 0.7874 -0.4064)
			(end -0.7874 -0.4064)
			(stroke
				(width 0.1524)
				(type default)
			)
			(layer "B.SilkS")
		)
		(fp_line
			(start -0.67945 0.3048)
			(end -0.120396 0.3048)
			(stroke
				(width 0.1)
				(type default)
			)
			(layer "B.Fab")
		)
		(fp_line
			(start -0.120396 0.3048)
			(end -0.120396 0.2794)
			(stroke
				(width 0.1)
				(type default)
			)
			(layer "B.Fab")
		)
		(fp_line
			(start 0.12065 0.3048)
			(end 0.67945 0.3048)
			(stroke
				(width 0.1)
				(type default)
			)
			(layer "B.Fab")
		)
		(fp_line
			(start 0.67945 0.3048)
			(end 0.67945 -0.305054)
			(stroke
				(width 0.1)
				(type default)
			)
			(layer "B.Fab")
		)
		(fp_line
			(start -0.120396 0.2794)
			(end 0.12065 0.2794)
			(stroke
				(width 0.1)
				(type default)
			)
			(layer "B.Fab")
		)
		(fp_line
			(start 0.12065 0.2794)
			(end 0.12065 0.3048)
			(stroke
				(width 0.1)
				(type default)
			)
			(layer "B.Fab")
		)
		(fp_line
			(start -0.12065 -0.2794)
			(end -0.12065 -0.3048)
			(stroke
				(width 0.1)
				(type default)
			)
			(layer "B.Fab")
		)
		(fp_line
			(start 0.12065 -0.2794)
			(end -0.12065 -0.2794)
			(stroke
				(width 0.1)
				(type default)
			)
			(layer "B.Fab")
		)
		(fp_line
			(start -0.67945 -0.3048)
			(end -0.67945 0.3048)
			(stroke
				(width 0.1)
				(type default)
			)
			(layer "B.Fab")
		)
		(fp_line
			(start -0.12065 -0.3048)
			(end -0.67945 -0.3048)
			(stroke
				(width 0.1)
				(type default)
			)
			(layer "B.Fab")
		)
		(fp_line
			(start 0.12065 -0.305054)
			(end 0.12065 -0.2794)
			(stroke
				(width 0.1)
				(type default)
			)
			(layer "B.Fab")
		)
		(fp_line
			(start 0.67945 -0.305054)
			(end 0.12065 -0.305054)
			(stroke
				(width 0.1)
				(type default)
			)
			(layer "B.Fab")
		)
		(pad "1" smd circle
			(at 0.40005 0 90)
			(size 0 0)
			(layers "B.Cu" "B.Mask" "B.Paste")
			(net "P52V_HS1_TEMP")
		)
		(pad "2" smd circle
			(at -0.40005 0 90)
			(size 0 0)
			(layers "B.Cu" "B.Mask" "B.Paste")
			(net "GND_FIELD_SIGNAL")
		)
	)
	(footprint ""
		(layer "B.Cu")
		(at 285.9024 -66.929 180)
		(property "Reference" "PR11"
			(at 0 0 0)
			(layer "B.SilkS")
			(hide yes)
			(effects
				(font
					(size 1.27 1.27)
				)
				(justify mirror)
			)
		)
		(property "Value" ""
			(at 0 0 0)
			(layer "B.Fab")
			(effects
				(font
					(size 1.27 1.27)
				)
				(justify mirror)
			)
		)
		(duplicate_pad_numbers_are_jumpers no)
		(fp_line
			(start 0.7874 0.4064)
			(end 0.7874 -0.4064)
			(stroke
				(width 0.1524)
				(type default)
			)
			(layer "B.SilkS")
		)
		(fp_line
			(start 0.7874 -0.4064)
			(end -0.7874 -0.4064)
			(stroke
				(width 0.1524)
				(type default)
			)
			(layer "B.SilkS")
		)
		(fp_line
			(start -0.7874 0.4064)
			(end 0.7874 0.4064)
			(stroke
				(width 0.1524)
				(type default)
			)
			(layer "B.SilkS")
		)
		(fp_line
			(start -0.7874 -0.4064)
			(end -0.7874 0.4064)
			(stroke
				(width 0.1524)
				(type default)
			)
			(layer "B.SilkS")
		)
		(fp_line
			(start 0.67945 0.3048)
			(end 0.67945 -0.305054)
			(stroke
				(width 0.1)
				(type default)
			)
			(layer "B.Fab")
		)
		(fp_line
			(start 0.67945 -0.305054)
			(end 0.12065 -0.305054)
			(stroke
				(width 0.1)
				(type default)
			)
			(layer "B.Fab")
		)
		(fp_line
			(start 0.12065 0.3048)
			(end 0.67945 0.3048)
			(stroke
				(width 0.1)
				(type default)
			)
			(layer "B.Fab")
		)
		(fp_line
			(start 0.12065 0.2794)
			(end 0.12065 0.3048)
			(stroke
				(width 0.1)
				(type default)
			)
			(layer "B.Fab")
		)
		(fp_line
			(start 0.12065 -0.2794)
			(end -0.12065 -0.2794)
			(stroke
				(width 0.1)
				(type default)
			)
			(layer "B.Fab")
		)
		(fp_line
			(start 0.12065 -0.305054)
			(end 0.12065 -0.2794)
			(stroke
				(width 0.1)
				(type default)
			)
			(layer "B.Fab")
		)
		(fp_line
			(start -0.120396 0.3048)
			(end -0.120396 0.2794)
			(stroke
				(width 0.1)
				(type default)
			)
			(layer "B.Fab")
		)
		(fp_line
			(start -0.120396 0.2794)
			(end 0.12065 0.2794)
			(stroke
				(width 0.1)
				(type default)
			)
			(layer "B.Fab")
		)
		(fp_line
			(start -0.12065 -0.2794)
			(end -0.12065 -0.3048)
			(stroke
				(width 0.1)
				(type default)
			)
			(layer "B.Fab")
		)
		(fp_line
			(start -0.12065 -0.3048)
			(end -0.67945 -0.3048)
			(stroke
				(width 0.1)
				(type default)
			)
			(layer "B.Fab")
		)
		(fp_line
			(start -0.67945 0.3048)
			(end -0.120396 0.3048)
			(stroke
				(width 0.1)
				(type default)
			)
			(layer "B.Fab")
		)
		(fp_line
			(start -0.67945 -0.3048)
			(end -0.67945 0.3048)
			(stroke
				(width 0.1)
				(type default)
			)
			(layer "B.Fab")
		)
		(pad "1" smd circle
			(at 0.40005 0)
			(size 0 0)
			(layers "B.Cu" "B.Mask" "B.Paste")
			(net "GND_FIELD_SIGNAL")
		)
		(pad "2" smd circle
			(at -0.40005 0)
			(size 0 0)
			(layers "B.Cu" "B.Mask" "B.Paste")
			(net "P52V_HS1_CLKIN")
		)
	)
	(footprint ""
		(layer "B.Cu")
		(at 158.034736 -77.216 -90)
		(property "Reference" "PR7016"
			(at 0 0 90)
			(layer "B.SilkS")
			(hide yes)
			(effects
				(font
					(size 1.27 1.27)
				)
				(justify mirror)
			)
		)
		(property "Value" ""
			(at 0 0 90)
			(layer "B.Fab")
			(effects
				(font
					(size 1.27 1.27)
				)
				(justify mirror)
			)
		)
		(duplicate_pad_numbers_are_jumpers no)
		(fp_line
			(start -0.7874 0.4064)
			(end 0.7874 0.4064)
			(stroke
				(width 0.1524)
				(type default)
			)
			(layer "B.SilkS")
		)
		(fp_line
			(start 0.7874 0.4064)
			(end 0.7874 -0.4064)
			(stroke
				(width 0.1524)
				(type default)
			)
			(layer "B.SilkS")
		)
		(fp_line
			(start -0.7874 -0.4064)
			(end -0.7874 0.4064)
			(stroke
				(width 0.1524)
				(type default)
			)
			(layer "B.SilkS")
		)
		(fp_line
			(start 0.7874 -0.4064)
			(end -0.7874 -0.4064)
			(stroke
				(width 0.1524)
				(type default)
			)
			(layer "B.SilkS")
		)
		(fp_line
			(start -0.67945 0.3048)
			(end -0.120396 0.3048)
			(stroke
				(width 0.1)
				(type default)
			)
			(layer "B.Fab")
		)
		(fp_line
			(start -0.120396 0.3048)
			(end -0.120396 0.2794)
			(stroke
				(width 0.1)
				(type default)
			)
			(layer "B.Fab")
		)
		(fp_line
			(start 0.12065 0.3048)
			(end 0.67945 0.3048)
			(stroke
				(width 0.1)
				(type default)
			)
			(layer "B.Fab")
		)
		(fp_line
			(start 0.67945 0.3048)
			(end 0.67945 -0.305054)
			(stroke
				(width 0.1)
				(type default)
			)
			(layer "B.Fab")
		)
		(fp_line
			(start -0.120396 0.2794)
			(end 0.12065 0.2794)
			(stroke
				(width 0.1)
				(type default)
			)
			(layer "B.Fab")
		)
		(fp_line
			(start 0.12065 0.2794)
			(end 0.12065 0.3048)
			(stroke
				(width 0.1)
				(type default)
			)
			(layer "B.Fab")
		)
		(fp_line
			(start -0.12065 -0.2794)
			(end -0.12065 -0.3048)
			(stroke
				(width 0.1)
				(type default)
			)
			(layer "B.Fab")
		)
		(fp_line
			(start 0.12065 -0.2794)
			(end -0.12065 -0.2794)
			(stroke
				(width 0.1)
				(type default)
			)
			(layer "B.Fab")
		)
		(fp_line
			(start -0.67945 -0.3048)
			(end -0.67945 0.3048)
			(stroke
				(width 0.1)
				(type default)
			)
			(layer "B.Fab")
		)
		(fp_line
			(start -0.12065 -0.3048)
			(end -0.67945 -0.3048)
			(stroke
				(width 0.1)
				(type default)
			)
			(layer "B.Fab")
		)
		(fp_line
			(start 0.12065 -0.305054)
			(end 0.12065 -0.2794)
			(stroke
				(width 0.1)
				(type default)
			)
			(layer "B.Fab")
		)
		(fp_line
			(start 0.67945 -0.305054)
			(end 0.12065 -0.305054)
			(stroke
				(width 0.1)
				(type default)
			)
			(layer "B.Fab")
		)
		(pad "1" smd circle
			(at 0.40005 0 90)
			(size 0 0)
			(layers "B.Cu" "B.Mask" "B.Paste")
			(net "P52V_HS2_MODE")
		)
		(pad "2" smd circle
			(at -0.40005 0 90)
			(size 0 0)
			(layers "B.Cu" "B.Mask" "B.Paste")
			(net "P52V_HS2_INTVCC")
		)
	)
	(footprint ""
		(layer "B.Cu")
		(at 295.402 -87.884 90)
		(property "Reference" "R5942"
			(at 0 0 90)
			(layer "B.SilkS")
			(hide yes)
			(effects
				(font
					(size 1.27 1.27)
				)
				(justify mirror)
			)
		)
		(property "Value" ""
			(at 0 0 90)
			(layer "B.Fab")
			(effects
				(font
					(size 1.27 1.27)
				)
				(justify mirror)
			)
		)
		(duplicate_pad_numbers_are_jumpers no)
		(fp_line
			(start 0.7874 -0.4064)
			(end -0.7874 -0.4064)
			(stroke
				(width 0.1524)
				(type default)
			)
			(layer "B.SilkS")
		)
		(fp_line
			(start -0.7874 -0.4064)
			(end -0.7874 0.4064)
			(stroke
				(width 0.1524)
				(type default)
			)
			(layer "B.SilkS")
		)
		(fp_line
			(start 0.7874 0.4064)
			(end 0.7874 -0.4064)
			(stroke
				(width 0.1524)
				(type default)
			)
			(layer "B.SilkS")
		)
		(fp_line
			(start -0.7874 0.4064)
			(end 0.7874 0.4064)
			(stroke
				(width 0.1524)
				(type default)
			)
			(layer "B.SilkS")
		)
		(fp_line
			(start 0.67945 -0.305054)
			(end 0.12065 -0.305054)
			(stroke
				(width 0.1)
				(type default)
			)
			(layer "B.Fab")
		)
		(fp_line
			(start 0.12065 -0.305054)
			(end 0.12065 -0.2794)
			(stroke
				(width 0.1)
				(type default)
			)
			(layer "B.Fab")
		)
		(fp_line
			(start -0.12065 -0.3048)
			(end -0.67945 -0.3048)
			(stroke
				(width 0.1)
				(type default)
			)
			(layer "B.Fab")
		)
		(fp_line
			(start -0.67945 -0.3048)
			(end -0.67945 0.3048)
			(stroke
				(width 0.1)
				(type default)
			)
			(layer "B.Fab")
		)
		(fp_line
			(start 0.12065 -0.2794)
			(end -0.12065 -0.2794)
			(stroke
				(width 0.1)
				(type default)
			)
			(layer "B.Fab")
		)
		(fp_line
			(start -0.12065 -0.2794)
			(end -0.12065 -0.3048)
			(stroke
				(width 0.1)
				(type default)
			)
			(layer "B.Fab")
		)
		(fp_line
			(start 0.12065 0.2794)
			(end 0.12065 0.3048)
			(stroke
				(width 0.1)
				(type default)
			)
			(layer "B.Fab")
		)
		(fp_line
			(start -0.120396 0.2794)
			(end 0.12065 0.2794)
			(stroke
				(width 0.1)
				(type default)
			)
			(layer "B.Fab")
		)
		(fp_line
			(start 0.67945 0.3048)
			(end 0.67945 -0.305054)
			(stroke
				(width 0.1)
				(type default)
			)
			(layer "B.Fab")
		)
		(fp_line
			(start 0.12065 0.3048)
			(end 0.67945 0.3048)
			(stroke
				(width 0.1)
				(type default)
			)
			(layer "B.Fab")
		)
		(fp_line
			(start -0.120396 0.3048)
			(end -0.120396 0.2794)
			(stroke
				(width 0.1)
				(type default)
			)
			(layer "B.Fab")
		)
		(fp_line
			(start -0.67945 0.3048)
			(end -0.120396 0.3048)
			(stroke
				(width 0.1)
				(type default)
			)
			(layer "B.Fab")
		)
		(pad "1" smd circle
			(at 0.40005 0 270)
			(size 0 0)
			(layers "B.Cu" "B.Mask" "B.Paste")
			(net "P3V3_AUX")
		)
		(pad "2" smd circle
			(at -0.40005 0 270)
			(size 0 0)
			(layers "B.Cu" "B.Mask" "B.Paste")
			(net "FM_HS1_EN_BUSBAR_BUF")
		)
	)
	(footprint ""
		(layer "B.Cu")
		(at 290.9824 -62.992 -90)
		(property "Reference" "R157"
			(at 0 0 90)
			(layer "B.SilkS")
			(hide yes)
			(effects
				(font
					(size 1.27 1.27)
				)
				(justify mirror)
			)
		)
		(property "Value" ""
			(at 0 0 90)
			(layer "B.Fab")
			(effects
				(font
					(size 1.27 1.27)
				)
				(justify mirror)
			)
		)
		(duplicate_pad_numbers_are_jumpers no)
		(fp_line
			(start -0.7874 0.4064)
			(end 0.7874 0.4064)
			(stroke
				(width 0.1524)
				(type default)
			)
			(layer "B.SilkS")
		)
		(fp_line
			(start 0.7874 0.4064)
			(end 0.7874 -0.4064)
			(stroke
				(width 0.1524)
				(type default)
			)
			(layer "B.SilkS")
		)
		(fp_line
			(start -0.7874 -0.4064)
			(end -0.7874 0.4064)
			(stroke
				(width 0.1524)
				(type default)
			)
			(layer "B.SilkS")
		)
		(fp_line
			(start 0.7874 -0.4064)
			(end -0.7874 -0.4064)
			(stroke
				(width 0.1524)
				(type default)
			)
			(layer "B.SilkS")
		)
		(fp_line
			(start -0.67945 0.3048)
			(end -0.120396 0.3048)
			(stroke
				(width 0.1)
				(type default)
			)
			(layer "B.Fab")
		)
		(fp_line
			(start -0.120396 0.3048)
			(end -0.120396 0.2794)
			(stroke
				(width 0.1)
				(type default)
			)
			(layer "B.Fab")
		)
		(fp_line
			(start 0.12065 0.3048)
			(end 0.67945 0.3048)
			(stroke
				(width 0.1)
				(type default)
			)
			(layer "B.Fab")
		)
		(fp_line
			(start 0.67945 0.3048)
			(end 0.67945 -0.305054)
			(stroke
				(width 0.1)
				(type default)
			)
			(layer "B.Fab")
		)
		(fp_line
			(start -0.120396 0.2794)
			(end 0.12065 0.2794)
			(stroke
				(width 0.1)
				(type default)
			)
			(layer "B.Fab")
		)
		(fp_line
			(start 0.12065 0.2794)
			(end 0.12065 0.3048)
			(stroke
				(width 0.1)
				(type default)
			)
			(layer "B.Fab")
		)
		(fp_line
			(start -0.12065 -0.2794)
			(end -0.12065 -0.3048)
			(stroke
				(width 0.1)
				(type default)
			)
			(layer "B.Fab")
		)
		(fp_line
			(start 0.12065 -0.2794)
			(end -0.12065 -0.2794)
			(stroke
				(width 0.1)
				(type default)
			)
			(layer "B.Fab")
		)
		(fp_line
			(start -0.67945 -0.3048)
			(end -0.67945 0.3048)
			(stroke
				(width 0.1)
				(type default)
			)
			(layer "B.Fab")
		)
		(fp_line
			(start -0.12065 -0.3048)
			(end -0.67945 -0.3048)
			(stroke
				(width 0.1)
				(type default)
			)
			(layer "B.Fab")
		)
		(fp_line
			(start 0.12065 -0.305054)
			(end 0.12065 -0.2794)
			(stroke
				(width 0.1)
				(type default)
			)
			(layer "B.Fab")
		)
		(fp_line
			(start 0.67945 -0.305054)
			(end 0.12065 -0.305054)
			(stroke
				(width 0.1)
				(type default)
			)
			(layer "B.Fab")
		)
		(pad "1" smd circle
			(at 0.40005 0 90)
			(size 0 0)
			(layers "B.Cu" "B.Mask" "B.Paste")
			(net "P52V_HS1_INTVCC")
		)
		(pad "2" smd circle
			(at -0.40005 0 90)
			(size 0 0)
			(layers "B.Cu" "B.Mask" "B.Paste")
			(net "P52V_HS1_ADR1")
		)
	)
)
